# T6G (Grand Teton) — schematic netlist excerpt (pin names and nets, part order shuffled) for the footprints in the layout excerpt that follows; sources: Cadence DE-HDL packaged netlist, KiCad conversion of 04192023_DAF0TMB3IC0_F0TG_MB_C_brd_V02_OCP.brd

PC224_1  Q_CAP  22UF 4V 20% X6S  pkg C0805  page 208 : A = PVDD11_S3_P0 ; B = GND
C2369  Q_CAP  22UF 4V 20% X6S  pkg C0402  page 73 : A = PVDDCR_CPU1_P1 ; B = GND
R1533  Q_RES  0 5% CHIP  pkg 0402LF  page 27 : A = CPU0_THERMTRIP_R_N ; B = CPU1_THERMTRIP_R_N

(kicad_pcb
	(version 20260206)
	(generator "pcbnew")
	(generator_version "10.0")
	(general
		(thickness 1.6)
		(legacy_teardrops no)
	)
	(paper "A4")
	(title_block
		(title "04192023_DAF0TMB3IC0_F0TG_MB_C_brd_V02_OCP.brd")
		(comment 1 "Grand Teton / footprints 6421-6423 of 8354")
	)
	(layers
		(0 "F.Cu" signal "TOP")
		(4 "In1.Cu" signal "GND")
		(6 "In2.Cu" signal "IN1")
		(8 "In3.Cu" signal "GND1")
		(10 "In4.Cu" signal "IN2")
		(12 "In5.Cu" signal "GND2")
		(14 "In6.Cu" signal "IN3")
		(16 "In7.Cu" signal "GND3")
		(18 "In8.Cu" signal "VCC")
		(20 "In9.Cu" signal "VCC1")
		(22 "In10.Cu" signal "GND4")
		(24 "In11.Cu" signal "IN4")
		(26 "In12.Cu" signal "GND5")
		(28 "In13.Cu" signal "IN5")
		(30 "In14.Cu" signal "GND6")
		(32 "In15.Cu" signal "IN6")
		(34 "In16.Cu" signal "GND7")
		(2 "B.Cu" signal "BOTTOM")
		(9 "F.Adhes" user "F.Adhesive")
		(11 "B.Adhes" user "B.Adhesive")
		(13 "F.Paste" user "Package Geometry/Pastemask Top")
		(15 "B.Paste" user "Package Geometry/Pastemask Bottom")
		(5 "F.SilkS" user "Ref Des/Silkscreen Top")
		(7 "B.SilkS" user "Ref Des/Silkscreen Bottom")
		(1 "F.Mask" user "Board Geometry/Soldermask Top")
		(3 "B.Mask" user "Board Geometry/Soldermask Bottom")
		(17 "Dwgs.User" user "User.Drawings")
		(19 "Cmts.User" user "User.Comments")
		(21 "Eco1.User" user "User.Eco1")
		(23 "Eco2.User" user "User.Eco2")
		(25 "Edge.Cuts" user "Board Geometry/Outline")
		(27 "Margin" user)
		(31 "F.CrtYd" user "Package Geometry/Place Bound Top")
		(29 "B.CrtYd" user "Package Geometry/Place Bound Bottom")
		(35 "F.Fab" user "Ref Des/Assembly Top")
		(33 "B.Fab" user "Ref Des/Assembly Bottom")
	)
	(footprint ""
		(layer "B.Cu")
		(at 116.781834 -272.284952)
		(property "Reference" "C2369"
			(at 0 0 0)
			(layer "B.SilkS")
			(hide yes)
			(effects
				(font
					(size 1.27 1.27)
				)
				(justify mirror)
			)
		)
		(property "Value" ""
			(at 0 0 0)
			(layer "B.Fab")
			(effects
				(font
					(size 1.27 1.27)
				)
				(justify mirror)
			)
		)
		(duplicate_pad_numbers_are_jumpers no)
		(fp_line
			(start -0.7874 -0.4064)
			(end -0.7874 0.4064)
			(stroke
				(width 0.1524)
				(type default)
			)
			(layer "B.SilkS")
		)
		(fp_line
			(start -0.7874 0.4064)
			(end 0.7874 0.4064)
			(stroke
				(width 0.1524)
				(type default)
			)
			(layer "B.SilkS")
		)
		(fp_line
			(start 0.7874 -0.4064)
			(end -0.7874 -0.4064)
			(stroke
				(width 0.1524)
				(type default)
			)
			(layer "B.SilkS")
		)
		(fp_line
			(start 0.7874 0.4064)
			(end 0.7874 -0.4064)
			(stroke
				(width 0.1524)
				(type default)
			)
			(layer "B.SilkS")
		)
		(fp_line
			(start -0.67945 -0.3048)
			(end -0.67945 0.3048)
			(stroke
				(width 0.1)
				(type default)
			)
			(layer "B.Fab")
		)
		(fp_line
			(start -0.67945 0.3048)
			(end -0.120396 0.3048)
			(stroke
				(width 0.1)
				(type default)
			)
			(layer "B.Fab")
		)
		(fp_line
			(start -0.12065 -0.3048)
			(end -0.67945 -0.3048)
			(stroke
				(width 0.1)
				(type default)
			)
			(layer "B.Fab")
		)
		(fp_line
			(start -0.12065 -0.2794)
			(end -0.12065 -0.3048)
			(stroke
				(width 0.1)
				(type default)
			)
			(layer "B.Fab")
		)
		(fp_line
			(start -0.120396 0.2794)
			(end 0.12065 0.2794)
			(stroke
				(width 0.1)
				(type default)
			)
			(layer "B.Fab")
		)
		(fp_line
			(start -0.120396 0.3048)
			(end -0.120396 0.2794)
			(stroke
				(width 0.1)
				(type default)
			)
			(layer "B.Fab")
		)
		(fp_line
			(start 0.12065 -0.305054)
			(end 0.12065 -0.2794)
			(stroke
				(width 0.1)
				(type default)
			)
			(layer "B.Fab")
		)
		(fp_line
			(start 0.12065 -0.2794)
			(end -0.12065 -0.2794)
			(stroke
				(width 0.1)
				(type default)
			)
			(layer "B.Fab")
		)
		(fp_line
			(start 0.12065 0.2794)
			(end 0.12065 0.3048)
			(stroke
				(width 0.1)
				(type default)
			)
			(layer "B.Fab")
		)
		(fp_line
			(start 0.12065 0.3048)
			(end 0.67945 0.3048)
			(stroke
				(width 0.1)
				(type default)
			)
			(layer "B.Fab")
		)
		(fp_line
			(start 0.67945 -0.305054)
			(end 0.12065 -0.305054)
			(stroke
				(width 0.1)
				(type default)
			)
			(layer "B.Fab")
		)
		(fp_line
			(start 0.67945 0.3048)
			(end 0.67945 -0.305054)
			(stroke
				(width 0.1)
				(type default)
			)
			(layer "B.Fab")
		)
		(pad "1" smd circle
			(at 0.40005 0 180)
			(size 0 0)
			(layers "B.Cu" "B.Mask" "B.Paste")
			(net "PVDDCR_CPU1_P1")
		)
		(pad "2" smd circle
			(at -0.40005 0 180)
			(size 0 0)
			(layers "B.Cu" "B.Mask" "B.Paste")
			(net "GND")
		)
	)
	(footprint ""
		(layer "B.Cu")
		(at 427.526958 -342.007952 -90)
		(property "Reference" "PC224_1"
			(at 0 0 90)
			(layer "B.SilkS")
			(hide yes)
			(effects
				(font
					(size 1.27 1.27)
				)
				(justify mirror)
			)
		)
		(property "Value" ""
			(at 0 0 90)
			(layer "B.Fab")
			(effects
				(font
					(size 1.27 1.27)
				)
				(justify mirror)
			)
		)
		(duplicate_pad_numbers_are_jumpers no)
		(fp_line
			(start -1.524 0.762)
			(end 1.524 0.762)
			(stroke
				(width 0.1524)
				(type default)
			)
			(layer "B.SilkS")
		)
		(fp_line
			(start 1.524 0.762)
			(end 1.524 -0.762)
			(stroke
				(width 0.1524)
				(type default)
			)
			(layer "B.SilkS")
		)
		(fp_line
			(start -1.524 -0.762)
			(end -1.524 0.762)
			(stroke
				(width 0.1524)
				(type default)
			)
			(layer "B.SilkS")
		)
		(fp_line
			(start 1.524 -0.762)
			(end -1.524 -0.762)
			(stroke
				(width 0.1524)
				(type default)
			)
			(layer "B.SilkS")
		)
		(fp_line
			(start -1.1049 0.724916)
			(end -1.1049 -0.724916)
			(stroke
				(width 0.1)
				(type default)
			)
			(layer "B.Fab")
		)
		(fp_line
			(start 1.1049 0.724916)
			(end -1.1049 0.724916)
			(stroke
				(width 0.1)
				(type default)
			)
			(layer "B.Fab")
		)
		(fp_line
			(start -1.1049 -0.724916)
			(end 1.1049 -0.724916)
			(stroke
				(width 0.1)
				(type default)
			)
			(layer "B.Fab")
		)
		(fp_line
			(start 1.1049 -0.724916)
			(end 1.1049 0.724916)
			(stroke
				(width 0.1)
				(type default)
			)
			(layer "B.Fab")
		)
		(pad "1" smd rect
			(at 0.889 0 270)
			(size 1.016 1.27)
			(layers "B.Cu" "B.Mask" "B.Paste")
			(net "PVDD11_S3_P0")
		)
		(pad "2" smd rect
			(at -0.889 0 270)
			(size 1.016 1.27)
			(layers "B.Cu" "B.Mask" "B.Paste")
			(net "GND")
		)
	)
	(footprint ""
		(layer "B.Cu")
		(at 182.737252 -97.112836 90)
		(property "Reference" "R1533"
			(at 0 0 90)
			(layer "B.SilkS")
			(hide yes)
			(effects
				(font
					(size 1.27 1.27)
				)
				(justify mirror)
			)
		)
		(property "Value" ""
			(at 0 0 90)
			(layer "B.Fab")
			(effects
				(font
					(size 1.27 1.27)
				)
				(justify mirror)
			)
		)
		(duplicate_pad_numbers_are_jumpers no)
		(fp_line
			(start 0.7874 -0.4064)
			(end -0.7874 -0.4064)
			(stroke
				(width 0.1524)
				(type default)
			)
			(layer "B.SilkS")
		)
		(fp_line
			(start -0.7874 -0.4064)
			(end -0.7874 0.4064)
			(stroke
				(width 0.1524)
				(type default)
			)
			(layer "B.SilkS")
		)
		(fp_line
			(start 0.7874 0.4064)
			(end 0.7874 -0.4064)
			(stroke
				(width 0.1524)
				(type default)
			)
			(layer "B.SilkS")
		)
		(fp_line
			(start -0.7874 0.4064)
			(end 0.7874 0.4064)
			(stroke
				(width 0.1524)
				(type default)
			)
			(layer "B.SilkS")
		)
		(fp_line
			(start 0.67945 -0.305054)
			(end 0.12065 -0.305054)
			(stroke
				(width 0.1)
				(type default)
			)
			(layer "B.Fab")
		)
		(fp_line
			(start 0.12065 -0.305054)
			(end 0.12065 -0.2794)
			(stroke
				(width 0.1)
				(type default)
			)
			(layer "B.Fab")
		)
		(fp_line
			(start -0.12065 -0.3048)
			(end -0.67945 -0.3048)
			(stroke
				(width 0.1)
				(type default)
			)
			(layer "B.Fab")
		)
		(fp_line
			(start -0.67945 -0.3048)
			(end -0.67945 0.3048)
			(stroke
				(width 0.1)
				(type default)
			)
			(layer "B.Fab")
		)
		(fp_line
			(start 0.12065 -0.2794)
			(end -0.12065 -0.2794)
			(stroke
				(width 0.1)
				(type default)
			)
			(layer "B.Fab")
		)
		(fp_line
			(start -0.12065 -0.2794)
			(end -0.12065 -0.3048)
			(stroke
				(width 0.1)
				(type default)
			)
			(layer "B.Fab")
		)
		(fp_line
			(start 0.12065 0.2794)
			(end 0.12065 0.3048)
			(stroke
				(width 0.1)
				(type default)
			)
			(layer "B.Fab")
		)
		(fp_line
			(start -0.120396 0.2794)
			(end 0.12065 0.2794)
			(stroke
				(width 0.1)
				(type default)
			)
			(layer "B.Fab")
		)
		(fp_line
			(start 0.67945 0.3048)
			(end 0.67945 -0.305054)
			(stroke
				(width 0.1)
				(type default)
			)
			(layer "B.Fab")
		)
		(fp_line
			(start 0.12065 0.3048)
			(end 0.67945 0.3048)
			(stroke
				(width 0.1)
				(type default)
			)
			(layer "B.Fab")
		)
		(fp_line
			(start -0.120396 0.3048)
			(end -0.120396 0.2794)
			(stroke
				(width 0.1)
				(type default)
			)
			(layer "B.Fab")
		)
		(fp_line
			(start -0.67945 0.3048)
			(end -0.120396 0.3048)
			(stroke
				(width 0.1)
				(type default)
			)
			(layer "B.Fab")
		)
		(pad "1" smd circle
			(at 0.40005 0 270)
			(size 0 0)
			(layers "B.Cu" "B.Mask" "B.Paste")
			(net "CPU0_THERMTRIP_R_N")
		)
		(pad "2" smd circle
			(at -0.40005 0 270)
			(size 0 0)
			(layers "B.Cu" "B.Mask" "B.Paste")
			(net "CPU1_THERMTRIP_R_N")
		)
	)
)
